G04 ================== begin FILE IDENTIFICATION RECORD ==================*
G04 Layout Name:  15968-1a.brd*
G04 Film Name:    BSMD*
G04 File Format:  Gerber RS274X*
G04 File Origin:  Cadence Allegro 16.5-S058*
G04 Origin Date:  Fri Oct 14 10:23:25 2016*
G04 *
G04 Layer:  VIA CLASS/PASTEMASK_BOTTOM*
G04 Layer:  PIN/PASTEMASK_BOTTOM*
G04 Layer:  PACKAGE GEOMETRY/PASTEMASK_BOTTOM*
G04 Layer:  DRAWING FORMAT/LAYER_PCB_STORY*
G04 Layer:  DRAWING FORMAT/LAYER_PAST_B*
G04 Layer:  BOARD GEOMETRY/PANEL_OUTLINE*
G04 *
G04 Offset:    (0.00 0.00)*
G04 Mirror:    No*
G04 Mode:      Positive*
G04 Rotation:  0*
G04 FullContactRelief:  No*
G04 UndefLineWidth:     6.00*
G04 ================== end FILE IDENTIFICATION RECORD ====================*
%FSLAX35Y35*MOIN*%
%IR0*IPPOS*OFA0.00000B0.00000*MIA0B0*SFA1.00000B1.00000*%
%AMMACRO27*
4,1,40,.011,.007,
.011,-.007,
.010939,-.007695,
.010759,-.008368,
.010464,-.009,
.010064,-.009571,
.009571,-.010064,
.009,-.010464,
.008368,-.010759,
.007695,-.010939,
.007,-.011,
-.007,-.011,
-.007695,-.010939,
-.008368,-.010759,
-.009,-.010464,
-.009571,-.010064,
-.010064,-.009571,
-.010464,-.009,
-.010759,-.008368,
-.010939,-.007695,
-.011,-.007,
-.011,.007,
-.010939,.007695,
-.010759,.008368,
-.010464,.009,
-.010064,.009571,
-.009571,.010064,
-.009,.010464,
-.008368,.010759,
-.007695,.010939,
-.007,.011,
.007,.011,
.007695,.010939,
.008368,.010759,
.009,.010464,
.009571,.010064,
.010064,.009571,
.010464,.009,
.010759,.008368,
.010939,.007695,
.011,.007,
0.0*
%
%ADD27MACRO27*%
%AMMACRO11*
4,1,40,-.017,-.013,
-.017,.013,
-.016939,.013695,
-.016759,.014368,
-.016464,.015,
-.016064,.015571,
-.015571,.016064,
-.015,.016464,
-.014368,.016759,
-.013695,.016939,
-.013,.017,
.013,.017,
.013695,.016939,
.014368,.016759,
.015,.016464,
.015571,.016064,
.016064,.015571,
.016464,.015,
.016759,.014368,
.016939,.013695,
.017,.013,
.017,-.013,
.016939,-.013695,
.016759,-.014368,
.016464,-.015,
.016064,-.015571,
.015571,-.016064,
.015,-.016464,
.014368,-.016759,
.013695,-.016939,
.013,-.017,
-.013,-.017,
-.013695,-.016939,
-.014368,-.016759,
-.015,-.016464,
-.015571,-.016064,
-.016064,-.015571,
-.016464,-.015,
-.016759,-.014368,
-.016939,-.013695,
-.017,-.013,
0.0*
%
%ADD11MACRO11*%
%AMMACRO37*
4,1,3,0.0,-.0125,
.025,.0125,
-.025,.0125,
0.0,-.0125,
0.0*
%
%ADD37MACRO37*%
%ADD40C,.04*%
%ADD36R,.05X.008*%
%AMMACRO32*
4,1,32,-.00137,.05008,
.025,.05008,
.025,.06208,
-.025,.06208,
-.025,-.06209,
.025,-.06209,
.025,-.05409,
-.00137,-.05409,
-.00137,-.04635,
.025,-.04635,
.025,-.03835,
-.00137,-.03835,
-.00137,-.0306,
.025,-.0306,
.025,-.0226,
-.00137,-.0226,
-.00137,-.01485,
.025,-.01485,
.025,-.00685,
-.00137,-.00685,
-.00137,.0009,
.025,.0009,
.025,.0089,
-.00137,.0089,
-.00137,.01665,
.025,.01665,
.025,.02465,
-.00137,.02465,
-.00137,.03239,
.025,.03239,
.025,.04039,
-.00137,.04039,
-.00137,.05008,
0.0*
%
%ADD32MACRO32*%
%ADD12C,.028*%
%ADD13C,.086*%
%AMMACRO24*
4,1,40,.007,-.011,
-.007,-.011,
-.007695,-.010939,
-.008368,-.010759,
-.009,-.010464,
-.009571,-.010064,
-.010064,-.009571,
-.010464,-.009,
-.010759,-.008368,
-.010939,-.007695,
-.011,-.007,
-.011,.007,
-.010939,.007695,
-.010759,.008368,
-.010464,.009,
-.010064,.009571,
-.009571,.010064,
-.009,.010464,
-.008368,.010759,
-.007695,.010939,
-.007,.011,
.007,.011,
.007695,.010939,
.008368,.010759,
.009,.010464,
.009571,.010064,
.010064,.009571,
.010464,.009,
.010759,.008368,
.010939,.007695,
.011,.007,
.011,-.007,
.010939,-.007695,
.010759,-.008368,
.010464,-.009,
.010064,-.009571,
.009571,-.010064,
.009,-.010464,
.008368,-.010759,
.007695,-.010939,
.007,-.011,
0.0*
%
%ADD24MACRO24*%
%AMMACRO19*
4,1,40,-.008,.012,
.008,.012,
.008695,.011939,
.009368,.011759,
.01,.011464,
.010571,.011064,
.011064,.010571,
.011464,.01,
.011759,.009368,
.011939,.008695,
.012,.008,
.012,-.008,
.011939,-.008695,
.011759,-.009368,
.011464,-.01,
.011064,-.010571,
.010571,-.011064,
.01,-.011464,
.009368,-.011759,
.008695,-.011939,
.008,-.012,
-.008,-.012,
-.008695,-.011939,
-.009368,-.011759,
-.01,-.011464,
-.010571,-.011064,
-.011064,-.010571,
-.011464,-.01,
-.011759,-.009368,
-.011939,-.008695,
-.012,-.008,
-.012,.008,
-.011939,.008695,
-.011759,.009368,
-.011464,.01,
-.011064,.010571,
-.010571,.011064,
-.01,.011464,
-.009368,.011759,
-.008695,.011939,
-.008,.012,
0.0*
%
%ADD19MACRO19*%
%AMMACRO30*
4,1,40,-.013,.017,
.013,.017,
.013695,.016939,
.014368,.016759,
.015,.016464,
.015571,.016064,
.016064,.015571,
.016464,.015,
.016759,.014368,
.016939,.013695,
.017,.013,
.017,-.013,
.016939,-.013695,
.016759,-.014368,
.016464,-.015,
.016064,-.015571,
.015571,-.016064,
.015,-.016464,
.014368,-.016759,
.013695,-.016939,
.013,-.017,
-.013,-.017,
-.013695,-.016939,
-.014368,-.016759,
-.015,-.016464,
-.015571,-.016064,
-.016064,-.015571,
-.016464,-.015,
-.016759,-.014368,
-.016939,-.013695,
-.017,-.013,
-.017,.013,
-.016939,.013695,
-.016759,.014368,
-.016464,.015,
-.016064,.015571,
-.015571,.016064,
-.015,.016464,
-.014368,.016759,
-.013695,.016939,
-.013,.017,
0.0*
%
%ADD30MACRO30*%
%AMMACRO15*
4,1,40,.017,.013,
.017,-.013,
.016939,-.013695,
.016759,-.014368,
.016464,-.015,
.016064,-.015571,
.015571,-.016064,
.015,-.016464,
.014368,-.016759,
.013695,-.016939,
.013,-.017,
-.013,-.017,
-.013695,-.016939,
-.014368,-.016759,
-.015,-.016464,
-.015571,-.016064,
-.016064,-.015571,
-.016464,-.015,
-.016759,-.014368,
-.016939,-.013695,
-.017,-.013,
-.017,.013,
-.016939,.013695,
-.016759,.014368,
-.016464,.015,
-.016064,.015571,
-.015571,.016064,
-.015,.016464,
-.014368,.016759,
-.013695,.016939,
-.013,.017,
.013,.017,
.013695,.016939,
.014368,.016759,
.015,.016464,
.015571,.016064,
.016064,.015571,
.016464,.015,
.016759,.014368,
.016939,.013695,
.017,.013,
0.0*
%
%ADD15MACRO15*%
%AMMACRO25*
4,1,40,.007,-.011,
-.007,-.011,
-.007695,-.010939,
-.008368,-.010759,
-.009,-.010464,
-.009571,-.010064,
-.010064,-.009571,
-.010464,-.009,
-.010759,-.008368,
-.010939,-.007695,
-.011,-.007,
-.011,.007,
-.010939,.007695,
-.010759,.008368,
-.010464,.009,
-.010064,.009571,
-.009571,.010064,
-.009,.010464,
-.008368,.010759,
-.007695,.010939,
-.007,.011,
.007,.011,
.007695,.010939,
.008368,.010759,
.009,.010464,
.009571,.010064,
.010064,.009571,
.010464,.009,
.010759,.008368,
.010939,.007695,
.011,.007,
.011,-.007,
.010939,-.007695,
.010759,-.008368,
.010464,-.009,
.010064,-.009571,
.009571,-.010064,
.009,-.010464,
.008368,-.010759,
.007695,-.010939,
.007,-.011,
0.0*
%
%ADD25MACRO25*%
%AMMACRO18*
4,1,40,-.008,.012,
.008,.012,
.008695,.011939,
.009368,.011759,
.01,.011464,
.010571,.011064,
.011064,.010571,
.011464,.01,
.011759,.009368,
.011939,.008695,
.012,.008,
.012,-.008,
.011939,-.008695,
.011759,-.009368,
.011464,-.01,
.011064,-.010571,
.010571,-.011064,
.01,-.011464,
.009368,-.011759,
.008695,-.011939,
.008,-.012,
-.008,-.012,
-.008695,-.011939,
-.009368,-.011759,
-.01,-.011464,
-.010571,-.011064,
-.011064,-.010571,
-.011464,-.01,
-.011759,-.009368,
-.011939,-.008695,
-.012,-.008,
-.012,.008,
-.011939,.008695,
-.011759,.009368,
-.011464,.01,
-.011064,.010571,
-.010571,.011064,
-.01,.011464,
-.009368,.011759,
-.008695,.011939,
-.008,.012,
0.0*
%
%ADD18MACRO18*%
%AMMACRO31*
4,1,40,-.013,.017,
.013,.017,
.013695,.016939,
.014368,.016759,
.015,.016464,
.015571,.016064,
.016064,.015571,
.016464,.015,
.016759,.014368,
.016939,.013695,
.017,.013,
.017,-.013,
.016939,-.013695,
.016759,-.014368,
.016464,-.015,
.016064,-.015571,
.015571,-.016064,
.015,-.016464,
.014368,-.016759,
.013695,-.016939,
.013,-.017,
-.013,-.017,
-.013695,-.016939,
-.014368,-.016759,
-.015,-.016464,
-.015571,-.016064,
-.016064,-.015571,
-.016464,-.015,
-.016759,-.014368,
-.016939,-.013695,
-.017,-.013,
-.017,.013,
-.016939,.013695,
-.016759,.014368,
-.016464,.015,
-.016064,.015571,
-.015571,.016064,
-.015,.016464,
-.014368,.016759,
-.013695,.016939,
-.013,.017,
0.0*
%
%ADD31MACRO31*%
%AMMACRO16*
4,1,40,.017,.013,
.017,-.013,
.016939,-.013695,
.016759,-.014368,
.016464,-.015,
.016064,-.015571,
.015571,-.016064,
.015,-.016464,
.014368,-.016759,
.013695,-.016939,
.013,-.017,
-.013,-.017,
-.013695,-.016939,
-.014368,-.016759,
-.015,-.016464,
-.015571,-.016064,
-.016064,-.015571,
-.016464,-.015,
-.016759,-.014368,
-.016939,-.013695,
-.017,-.013,
-.017,.013,
-.016939,.013695,
-.016759,.014368,
-.016464,.015,
-.016064,.015571,
-.015571,.016064,
-.015,.016464,
-.014368,.016759,
-.013695,.016939,
-.013,.017,
.013,.017,
.013695,.016939,
.014368,.016759,
.015,.016464,
.015571,.016064,
.016064,.015571,
.016464,.015,
.016759,.014368,
.016939,.013695,
.017,.013,
0.0*
%
%ADD16MACRO16*%
%ADD35R,.05X.012*%
%AMMACRO38*
4,1,3,.025,-.0125,
0.0,.0125,
-.025,-.0125,
.025,-.0125,
0.0*
%
%ADD38MACRO38*%
%ADD34R,.052X.012*%
%ADD14R,.128X.107*%
%ADD17R,.045X.055*%
%ADD39R,.055X.045*%
%ADD33R,.014X.089*%
%AMMACRO28*
4,1,40,-.007,.011,
.007,.011,
.007695,.010939,
.008368,.010759,
.009,.010464,
.009571,.010064,
.010064,.009571,
.010464,.009,
.010759,.008368,
.010939,.007695,
.011,.007,
.011,-.007,
.010939,-.007695,
.010759,-.008368,
.010464,-.009,
.010064,-.009571,
.009571,-.010064,
.009,-.010464,
.008368,-.010759,
.007695,-.010939,
.007,-.011,
-.007,-.011,
-.007695,-.010939,
-.008368,-.010759,
-.009,-.010464,
-.009571,-.010064,
-.010064,-.009571,
-.010464,-.009,
-.010759,-.008368,
-.010939,-.007695,
-.011,-.007,
-.011,.007,
-.010939,.007695,
-.010759,.008368,
-.010464,.009,
-.010064,.009571,
-.009571,.010064,
-.009,.010464,
-.008368,.010759,
-.007695,.010939,
-.007,.011,
0.0*
%
%ADD28MACRO28*%
%AMMACRO23*
4,1,40,.008,-.012,
-.008,-.012,
-.008695,-.011939,
-.009368,-.011759,
-.01,-.011464,
-.010571,-.011064,
-.011064,-.010571,
-.011464,-.01,
-.011759,-.009368,
-.011939,-.008695,
-.012,-.008,
-.012,.008,
-.011939,.008695,
-.011759,.009368,
-.011464,.01,
-.011064,.010571,
-.010571,.011064,
-.01,.011464,
-.009368,.011759,
-.008695,.011939,
-.008,.012,
.008,.012,
.008695,.011939,
.009368,.011759,
.01,.011464,
.010571,.011064,
.011064,.010571,
.011464,.01,
.011759,.009368,
.011939,.008695,
.012,.008,
.012,-.008,
.011939,-.008695,
.011759,-.009368,
.011464,-.01,
.011064,-.010571,
.010571,-.011064,
.01,-.011464,
.009368,-.011759,
.008695,-.011939,
.008,-.012,
0.0*
%
%ADD23MACRO23*%
%AMMACRO21*
4,1,40,.012,.008,
.012,-.008,
.011939,-.008695,
.011759,-.009368,
.011464,-.01,
.011064,-.010571,
.010571,-.011064,
.01,-.011464,
.009368,-.011759,
.008695,-.011939,
.008,-.012,
-.008,-.012,
-.008695,-.011939,
-.009368,-.011759,
-.01,-.011464,
-.010571,-.011064,
-.011064,-.010571,
-.011464,-.01,
-.011759,-.009368,
-.011939,-.008695,
-.012,-.008,
-.012,.008,
-.011939,.008695,
-.011759,.009368,
-.011464,.01,
-.011064,.010571,
-.010571,.011064,
-.01,.011464,
-.009368,.011759,
-.008695,.011939,
-.008,.012,
.008,.012,
.008695,.011939,
.009368,.011759,
.01,.011464,
.010571,.011064,
.011064,.010571,
.011464,.01,
.011759,.009368,
.011939,.008695,
.012,.008,
0.0*
%
%ADD21MACRO21*%
%AMMACRO26*
4,1,40,.011,.007,
.011,-.007,
.010939,-.007695,
.010759,-.008368,
.010464,-.009,
.010064,-.009571,
.009571,-.010064,
.009,-.010464,
.008368,-.010759,
.007695,-.010939,
.007,-.011,
-.007,-.011,
-.007695,-.010939,
-.008368,-.010759,
-.009,-.010464,
-.009571,-.010064,
-.010064,-.009571,
-.010464,-.009,
-.010759,-.008368,
-.010939,-.007695,
-.011,-.007,
-.011,.007,
-.010939,.007695,
-.010759,.008368,
-.010464,.009,
-.010064,.009571,
-.009571,.010064,
-.009,.010464,
-.008368,.010759,
-.007695,.010939,
-.007,.011,
.007,.011,
.007695,.010939,
.008368,.010759,
.009,.010464,
.009571,.010064,
.010064,.009571,
.010464,.009,
.010759,.008368,
.010939,.007695,
.011,.007,
0.0*
%
%ADD26MACRO26*%
%AMMACRO10*
4,1,40,-.017,-.013,
-.017,.013,
-.016939,.013695,
-.016759,.014368,
-.016464,.015,
-.016064,.015571,
-.015571,.016064,
-.015,.016464,
-.014368,.016759,
-.013695,.016939,
-.013,.017,
.013,.017,
.013695,.016939,
.014368,.016759,
.015,.016464,
.015571,.016064,
.016064,.015571,
.016464,.015,
.016759,.014368,
.016939,.013695,
.017,.013,
.017,-.013,
.016939,-.013695,
.016759,-.014368,
.016464,-.015,
.016064,-.015571,
.015571,-.016064,
.015,-.016464,
.014368,-.016759,
.013695,-.016939,
.013,-.017,
-.013,-.017,
-.013695,-.016939,
-.014368,-.016759,
-.015,-.016464,
-.015571,-.016064,
-.016064,-.015571,
-.016464,-.015,
-.016759,-.014368,
-.016939,-.013695,
-.017,-.013,
0.0*
%
%ADD10MACRO10*%
%AMMACRO29*
4,1,40,-.007,.011,
.007,.011,
.007695,.010939,
.008368,.010759,
.009,.010464,
.009571,.010064,
.010064,.009571,
.010464,.009,
.010759,.008368,
.010939,.007695,
.011,.007,
.011,-.007,
.010939,-.007695,
.010759,-.008368,
.010464,-.009,
.010064,-.009571,
.009571,-.010064,
.009,-.010464,
.008368,-.010759,
.007695,-.010939,
.007,-.011,
-.007,-.011,
-.007695,-.010939,
-.008368,-.010759,
-.009,-.010464,
-.009571,-.010064,
-.010064,-.009571,
-.010464,-.009,
-.010759,-.008368,
-.010939,-.007695,
-.011,-.007,
-.011,.007,
-.010939,.007695,
-.010759,.008368,
-.010464,.009,
-.010064,.009571,
-.009571,.010064,
-.009,.010464,
-.008368,.010759,
-.007695,.010939,
-.007,.011,
0.0*
%
%ADD29MACRO29*%
%AMMACRO22*
4,1,40,.008,-.012,
-.008,-.012,
-.008695,-.011939,
-.009368,-.011759,
-.01,-.011464,
-.010571,-.011064,
-.011064,-.010571,
-.011464,-.01,
-.011759,-.009368,
-.011939,-.008695,
-.012,-.008,
-.012,.008,
-.011939,.008695,
-.011759,.009368,
-.011464,.01,
-.011064,.010571,
-.010571,.011064,
-.01,.011464,
-.009368,.011759,
-.008695,.011939,
-.008,.012,
.008,.012,
.008695,.011939,
.009368,.011759,
.01,.011464,
.010571,.011064,
.011064,.010571,
.011464,.01,
.011759,.009368,
.011939,.008695,
.012,.008,
.012,-.008,
.011939,-.008695,
.011759,-.009368,
.011464,-.01,
.011064,-.010571,
.010571,-.011064,
.01,-.011464,
.009368,-.011759,
.008695,-.011939,
.008,-.012,
0.0*
%
%ADD22MACRO22*%
%AMMACRO20*
4,1,40,.012,.008,
.012,-.008,
.011939,-.008695,
.011759,-.009368,
.011464,-.01,
.011064,-.010571,
.010571,-.011064,
.01,-.011464,
.009368,-.011759,
.008695,-.011939,
.008,-.012,
-.008,-.012,
-.008695,-.011939,
-.009368,-.011759,
-.01,-.011464,
-.010571,-.011064,
-.011064,-.010571,
-.011464,-.01,
-.011759,-.009368,
-.011939,-.008695,
-.012,-.008,
-.012,.008,
-.011939,.008695,
-.011759,.009368,
-.011464,.01,
-.011064,.010571,
-.010571,.011064,
-.01,.011464,
-.009368,.011759,
-.008695,.011939,
-.008,.012,
.008,.012,
.008695,.011939,
.009368,.011759,
.01,.011464,
.010571,.011064,
.011064,.010571,
.011464,.01,
.011759,.009368,
.011939,.008695,
.012,.008,
0.0*
%
%ADD20MACRO20*%
%ADD41C,.02*%
%ADD42C,.005*%
%ADD43C,.006*%
G75*
%LPD*%
G75*
G54D10*
X24400Y65400D03*
X70800Y65700D03*
G54D20*
X34700Y82900D03*
X52567Y56182D03*
G54D11*
X24400Y59800D03*
X70800Y60100D03*
G54D21*
X31100Y82900D03*
X48967Y56182D03*
G54D30*
X44800Y85200D03*
G54D12*
X28000Y69800D03*
X26400Y42900D03*
X27800Y75300D03*
X84100Y-19500D03*
X106900Y15700D03*
X102700Y2000D03*
X98200Y6200D03*
X91363Y12538D03*
X76600Y85700D03*
X93200Y69100D03*
X90300Y59600D03*
X45946Y93127D03*
X39700Y66400D03*
X51600Y89900D03*
X55300Y86600D03*
X44500Y64500D03*
X79600Y63900D03*
X36847Y157992D03*
X55500Y168400D03*
X95800Y175700D03*
X105400Y168500D03*
X71500Y172300D03*
X43400Y191700D03*
X83500Y192900D03*
X96000Y195800D03*
X156600Y4900D03*
X126517Y-4483D03*
X109300Y-28000D03*
X125000Y36300D03*
X173600Y39200D03*
X161400Y62500D03*
X154300Y60200D03*
X120200Y78900D03*
X113600Y90100D03*
X108200Y100300D03*
X118800Y94600D03*
X173800Y171200D03*
X113600Y164600D03*
X168800Y169600D03*
X153700Y182800D03*
X184500Y184800D03*
X183900Y189900D03*
X181600Y194800D03*
X187400Y195900D03*
X169200Y188000D03*
X238400Y89300D03*
X221400Y179200D03*
X203700Y194000D03*
X260700Y197900D03*
X246200Y193600D03*
X209800Y183700D03*
X342100Y179200D03*
X274479Y167895D03*
X293300Y188200D03*
X426600Y-20400D03*
X427800Y74900D03*
X351300Y82000D03*
X353900Y29900D03*
X350500Y46600D03*
X426500Y26900D03*
X417700Y27800D03*
X507600Y204400D03*
X523000Y68700D03*
X524200Y167800D03*
X517900Y157400D03*
X555300Y172700D03*
X544200Y169500D03*
X515800Y219500D03*
X589800Y200900D03*
G54D22*
X36500Y71300D03*
G54D31*
X39200Y85200D03*
G54D13*
X14794Y226306D03*
X542107Y17432D03*
X585785Y228866D03*
G54D40*
X40794Y230682D03*
X37095Y524125D03*
X540347Y32747D03*
X572386Y532294D03*
X594107Y-26510D03*
X599868Y229462D03*
G54D41*
G01X-84798Y-164972D02*
Y-244972D01*
G01D02*
X1172402D01*
G01X-88798Y-148972D02*
G02I-12000J0D01*
G01X-93948D02*
G02I-6850J0D01*
G01X-100798Y-164972D02*
Y-132972D01*
G01X-84798Y-148972D02*
X-116798D01*
G01X-84798Y-164972D02*
X1172402D01*
G01X-84798Y-200472D02*
X1172402D01*
G01X384902Y-164972D02*
Y-244972D01*
G01X522402Y-164972D02*
Y-244972D01*
G01X637402Y-164972D02*
Y-244972D01*
G01X804902Y-164972D02*
Y-244972D01*
G01X974902Y-164972D02*
Y-244972D01*
G01X1172402Y-164972D02*
Y-244972D01*
G01X1200402Y-148972D02*
G02I-12000J0D01*
G01X1195252D02*
G02I-6850J0D01*
G01X1188402Y-164972D02*
Y-132972D01*
G01X1204402Y-148972D02*
X1172402D01*
G54D23*
X36500Y74900D03*
G54D14*
X58400Y25157D03*
Y47243D03*
G54D32*
X62437Y70885D03*
G54D42*
G01X-21653Y-58346D02*
G03X-6653Y-73346I15000J0D01*
G01X65080D02*
X-6653D01*
G01X9506Y0D02*
X69017D01*
G01X6722Y1153D02*
G03X9506Y0I2784J2784D01*
G01X1154Y6721D02*
X6722Y1153D01*
G01X1Y9505D02*
G03X1154Y6721I3937J0D01*
G01X1Y238051D02*
Y9505D01*
G01Y238051D02*
Y9505D01*
G01X-21653Y238051D02*
Y9505D01*
G01X1D02*
G03X1154Y6721I3937J0D01*
G01X-7873Y9505D02*
G03X-4414Y1153I11811J-1D01*
G01X1154Y6721D02*
X6722Y1153D01*
G01X-4414D02*
X1154Y-4415D01*
G01X6722Y1153D02*
G03X9506Y0I2784J2784D01*
G01X1154Y-4415D02*
G03X9506Y-7874I8351J8352D01*
G01Y0D02*
X69017D01*
G01X9506Y-7874D02*
X14917D01*
G01X-21653Y9505D02*
Y-58346D01*
G01X14917Y-7874D02*
G03Y0I0J3937D01*
G01X-7873Y50852D02*
Y9505D01*
G01Y81561D02*
G03X1I3937J-1D01*
G01Y50852D02*
G03X-7873I-3937J0D01*
G01Y186482D02*
Y81561D01*
G01X13443Y249862D02*
X611812D01*
G01X10659Y251015D02*
G03X13443Y249862I2784J2784D01*
G01X1154Y260520D02*
X10659Y251015D01*
G01X3938Y241988D02*
G03X1Y238051I0J-3937D01*
G01X602307Y241988D02*
X3938D01*
G01X602307D02*
X3938D01*
G01D02*
G03X1Y238051I0J-3937D01*
G01X-7873D02*
Y217191D01*
G01X1154Y260520D02*
X10659Y251015D01*
G01D02*
G03X13443Y249862I2784J2784D01*
G01D02*
X611812D01*
G01X-21653Y238051D02*
Y534327D01*
G01X-7873Y238051D02*
Y263304D01*
G01Y217191D02*
G03X1I3937J-1D01*
G01Y186482D02*
G03X-7873I-3937J0D01*
G01X1Y263304D02*
G03X1154Y260520I3937J0D01*
G01X1Y328602D02*
Y263304D01*
G01X3938Y332539D02*
G03X1Y328602I0J-3937D01*
G01X53151Y332539D02*
X3938D01*
G01X53151D02*
X3938D01*
G01D02*
G03X1Y328602I0J-3937D01*
G01X3938Y340413D02*
G03X-7873Y328602I0J-11811D01*
G01X1D02*
Y263304D01*
G01X-7873Y328602D02*
Y263304D01*
G01X1D02*
G03X1154Y260520I3937J0D01*
G01X10965Y332539D02*
G03Y340413I0J3937D01*
G01D02*
X3938D01*
G01X-6653Y565196D02*
G03X-21653Y550196I0J-15000D01*
G01X67796Y565196D02*
X-6653D01*
G01X-21653Y542201D02*
Y550196D01*
G01Y534327D02*
G03Y542201I0J3937D01*
G01X74922Y-73346D02*
X175828D01*
G01X72954Y-71378D02*
X74922Y-73346D01*
G01X72954Y-3937D02*
Y-71378D01*
G01X65080Y-7874D02*
Y-71772D01*
G01D02*
Y-73346D01*
G01X72954Y-3937D02*
G03X69017Y0I-3937J0D01*
G01X72954Y-3937D02*
G03X69017Y0I-3937J0D01*
G01X45626D02*
G03Y-7874I0J-3937D01*
G01D02*
X65080D01*
G01X51397Y241988D02*
G03Y249862I0J3937D01*
G01X93906D02*
G03Y241988I0J-3937D01*
G01X53151Y332539D02*
G03X57088Y336476I0J3937D01*
G01Y482345D02*
Y336476D01*
G01Y482345D02*
Y336476D01*
G01X53151Y332539D02*
G03X57088Y336476I0J3937D01*
G01X41674Y340413D02*
G03Y332539I0J-3937D01*
G01X49214Y340413D02*
X41674D01*
G01X49214Y442487D02*
Y340413D01*
G01X67796Y565196D02*
Y499724D01*
G01X75670Y563228D02*
Y495787D01*
G01X58241Y485129D02*
G03X57088Y482345I2784J-2784D01*
G01X63808Y490697D02*
X58241Y485129D01*
G01X66592Y491850D02*
G03X63808Y490697I0J-3937D01*
G01X71733Y491850D02*
X66592D01*
G01X71733D02*
G03X75670Y495787I0J3937D01*
G01X67796Y499724D02*
X66592D01*
G01Y491850D02*
G03X63808Y490697I0J-3937D01*
G01X66592Y499724D02*
G03X58240Y496265I-1J-11811D01*
G01X63808Y490697D02*
X58241Y485129D01*
G01X58240Y496264D02*
X52673Y490696D01*
G01X58241Y485129D02*
G03X57088Y482345I2784J-2784D01*
G01X52673Y490697D02*
G03X49214Y482343I8352J-8351D01*
G01Y482345D02*
Y473195D01*
G01X57088Y442487D02*
G03X49214I-3937J-1D01*
G01Y473195D02*
G03X57088I3937J0D01*
G01X77639Y565196D02*
X75670Y563228D01*
G01X173111Y565196D02*
X77639D01*
G01X177796Y-71378D02*
Y-52874D01*
G01X175828Y-73346D02*
X177796Y-71378D01*
G01X187245Y-52874D02*
G03X177796I-4725J0D01*
G01X175080Y563228D02*
X173111Y565196D01*
G01X175080Y534488D02*
Y563228D01*
G01Y534488D02*
G03X175867Y533700I787J-1D01*
G01X209529D02*
X175867D01*
G01X189214Y-73346D02*
X403466D01*
G01X187245Y-71378D02*
X189214Y-73346D01*
G01X187245Y-52874D02*
Y-71378D01*
G01X209529Y533700D02*
G03X210316Y534488I0J787D01*
G01Y563228D02*
Y534488D01*
G01X212284Y565196D02*
X210316Y563228D01*
G01X426536Y565196D02*
X212284D01*
G01X405434Y-71378D02*
Y-42638D01*
G01X403466Y-73346D02*
X405434Y-71378D01*
G01X406221Y-41850D02*
X439883D01*
G01X406221D02*
G03X405434Y-42638I1J-788D01*
G01X428505Y563228D02*
X426536Y565196D01*
G01X442639Y-73346D02*
X538111D01*
G01X440670Y-71378D02*
X442639Y-73346D01*
G01X440670Y-42638D02*
Y-71378D01*
G01Y-42638D02*
G03X439883Y-41850I-787J1D01*
G01X428504Y544723D02*
Y563227D01*
G01Y544723D02*
G03X437953I4724J0D01*
G01Y563227D02*
Y544723D01*
G01X428505Y544724D02*
Y563228D01*
G01Y544724D02*
G03X437954I4725J0D01*
G01Y563228D02*
Y544724D01*
G01X439922Y565196D02*
X437954Y563228D01*
G01X540828Y565196D02*
X439922D01*
G01X547954Y-73346D02*
X622403D01*
G01X547954D02*
Y-7874D01*
G01X540080Y-71378D02*
Y-3937D01*
G01X538111Y-73346D02*
X540080Y-71378D01*
G01X558662Y9505D02*
Y155374D01*
G01X557509Y6721D02*
G03X558662Y9505I-2784J2784D01*
G01X551942Y1153D02*
X557509Y6721D01*
G01X549158Y0D02*
G03X551942Y1153I0J3937D01*
G01X544017Y0D02*
X549158D01*
G01X544017D02*
G03X540080Y-3937I0J-3937D01*
G01X547954Y-7874D02*
X549158D01*
G01Y0D02*
G03X551942Y1153I0J3937D01*
G01X549158Y-7875D02*
G03X557510Y-4415I0J11811D01*
G01X551942Y1153D02*
X557509Y6721D01*
G01X557510Y-4414D02*
X563077Y1154D01*
G01X557509Y6721D02*
G03X558662Y9505I-2784J2784D01*
G01X563077Y1153D02*
G03X566536Y9507I-8352J8351D01*
G01X558662Y9505D02*
Y155374D01*
G01X566536Y9505D02*
Y18655D01*
G01D02*
G03X558662I-3937J-1D01*
G01Y49363D02*
G03X566536I3937J0D01*
G01D02*
Y151437D01*
G01X562599Y159311D02*
X611812D01*
G01X562599D02*
G03X558662Y155374I0J-3937D01*
G01X562599Y159311D02*
G03X558662Y155374I0J-3937D01*
G01X562599Y159311D02*
X611812D01*
G01X566536Y151437D02*
X574076D01*
G01D02*
G03Y159311I0J3937D01*
G01X564353Y249862D02*
G03Y241988I0J-3937D01*
G01X521844D02*
G03Y249862I0J3937D01*
G01X542796Y495787D02*
Y563228D01*
G01Y495787D02*
G03X546733Y491850I3937J0D01*
G01X606244D02*
X546733D01*
G01X606244D02*
X546733D01*
G01X542796Y495787D02*
G03X546733Y491850I3937J0D01*
G01X550670Y499724D02*
Y563622D01*
G01X570124Y491850D02*
G03Y499724I0J3937D01*
G01D02*
X550670D01*
G01Y565196D02*
X622403D01*
G01X542796Y563228D02*
X540828Y565196D01*
G01X550670Y563622D02*
Y565196D01*
G01X622403Y-73346D02*
G03X637403Y-58346I0J15000D01*
G01Y253799D02*
Y-58346D01*
G01X615749Y163248D02*
Y228546D01*
G01X611812Y159311D02*
G03X615749Y163248I0J3937D01*
G01X611812Y159311D02*
G03X615749Y163248I0J3937D01*
G01X611812Y151437D02*
G03X623623Y163248I0J11811D01*
G01X615749D02*
Y228546D01*
G01X623623Y163248D02*
Y228546D01*
G01X604785Y159311D02*
G03Y151437I0J-3937D01*
G01D02*
X611812D01*
G01X615749Y253799D02*
Y482345D01*
G01X611812Y249862D02*
G03X615749Y253799I0J3937D01*
G01X605091Y240835D02*
G03X602307Y241988I-2784J-2784D01*
G01X614596Y231330D02*
X605091Y240835D01*
G01X615749Y228546D02*
G03X614596Y231330I-3937J0D01*
G01X615749Y228546D02*
G03X614596Y231330I-3937J0D01*
G01D02*
X605091Y240835D01*
G01D02*
G03X602307Y241988I-2784J-2784D01*
G01X611812Y249862D02*
G03X615749Y253799I0J3937D01*
G01D02*
Y482345D01*
G01X623623Y253799D02*
Y274659D01*
G01X637403Y253799D02*
Y482345D01*
G01X623623Y228546D02*
Y253799D01*
G01Y274659D02*
G03X615749I-3937J0D01*
G01Y305368D02*
G03X623623I3937J0D01*
G01D02*
Y410289D01*
G01D02*
G03X615749I-3937J0D01*
G01X609028Y490697D02*
G03X606244Y491850I-2784J-2784D01*
G01X614596Y485129D02*
X609028Y490697D01*
G01X615749Y482345D02*
G03X614596Y485129I-3937J0D01*
G01X615749Y482345D02*
G03X614596Y485129I-3937J0D01*
G01X623623Y482345D02*
G03X620164Y490697I-11811J1D01*
G01X614596Y485129D02*
X609028Y490697D01*
G01X620164D02*
X614596Y496265D01*
G01X609028Y490697D02*
G03X606244Y491850I-2784J-2784D01*
G01X614596Y496265D02*
G03X606244Y499724I-8351J-8352D01*
G01D02*
X600833D01*
G01X637403Y482345D02*
Y550196D01*
G01X600833Y499724D02*
G03Y491850I0J-3937D01*
G01X615749Y440998D02*
G03X623623I3937J0D01*
G01D02*
Y482345D01*
G01X637403Y550196D02*
G03X622403Y565196I-15000J0D01*
G54D33*
X55819Y75234D03*
Y64366D03*
X58181D03*
G54D15*
X40900Y49500D03*
G54D24*
X31200Y79000D03*
X75300Y60000D03*
X32700Y67300D03*
G54D43*
G01X-65001Y-234972D02*
Y-217472D01*
X-60635D01*
X-58888Y-218347D01*
X-57578Y-219514D01*
X-56486Y-221263D01*
X-55613Y-223306D01*
X-55395Y-226222D01*
X-55613Y-229139D01*
X-56486Y-231181D01*
X-57578Y-232931D01*
X-58888Y-234097D01*
X-60635Y-234972D01*
X-65001D01*
G01X-48157Y-217472D02*
X-42698Y-234972D01*
X-37239Y-217472D01*
G01X-25198D02*
Y-234972D01*
G01X-30220Y-217472D02*
X-20176D01*
G01X5435Y-234972D02*
Y-217472D01*
X10894D01*
X12640Y-218347D01*
X13732Y-219514D01*
X14169Y-221847D01*
X13732Y-224181D01*
X12422Y-225639D01*
X10894Y-226514D01*
X5435D01*
G01X10894D02*
X14169Y-234972D01*
G01X27302Y-223306D02*
Y-234972D01*
G01Y-218639D02*
X26865Y-218347D01*
Y-217764D01*
X27302Y-217472D01*
X27739Y-217764D01*
Y-218347D01*
X27302Y-218639D01*
G01X41527Y-232931D02*
X42619Y-234097D01*
X44147Y-234972D01*
X45457D01*
X46767Y-234389D01*
X47640Y-233514D01*
X48077Y-232348D01*
X47859Y-230597D01*
X46985Y-229722D01*
X43055Y-227972D01*
X42182Y-225930D01*
X42619Y-224472D01*
X43492Y-223597D01*
X44802Y-223306D01*
X46112Y-223597D01*
X47422Y-224472D01*
G01X59027Y-227097D02*
X66014D01*
X65359Y-225055D01*
X64267Y-223889D01*
X62739Y-223306D01*
X61210Y-223597D01*
X59900Y-224472D01*
X59027Y-226514D01*
X58590Y-228264D01*
Y-230014D01*
X59027Y-231764D01*
X60119Y-233514D01*
X61429Y-234680D01*
X62957Y-234972D01*
X64485Y-234389D01*
X66014Y-232639D01*
G01X76745Y-234972D02*
Y-223306D01*
G01Y-225639D02*
X77837Y-224472D01*
X78929Y-223597D01*
X80457Y-223306D01*
X81548Y-223597D01*
X82859Y-224472D01*
G01X119605Y-218931D02*
X118295Y-218055D01*
X116767Y-217472D01*
X115020D01*
X113055Y-218347D01*
X111527Y-219805D01*
X110435Y-221556D01*
X109562Y-224472D01*
X109343Y-227097D01*
X109780Y-229722D01*
X110435Y-231472D01*
X111745Y-233222D01*
X113274Y-234389D01*
X114802Y-234972D01*
X116330D01*
X117859Y-234389D01*
X119169Y-233514D01*
X120261Y-232348D01*
G01X136232Y-234972D02*
Y-223306D01*
G01Y-225347D02*
X135359Y-224181D01*
X134048Y-223597D01*
X132520Y-223306D01*
X130992Y-223889D01*
X129682Y-225055D01*
X128808Y-226805D01*
X128372Y-229139D01*
X128808Y-231472D01*
X129682Y-233222D01*
X130992Y-234389D01*
X132520Y-234972D01*
X134048Y-234680D01*
X135359Y-233806D01*
X136232Y-232639D01*
G01X146745Y-234972D02*
Y-223306D01*
G01Y-225639D02*
X147837Y-224472D01*
X148929Y-223597D01*
X150457Y-223306D01*
X151548Y-223597D01*
X152859Y-224472D01*
G01X171232Y-217472D02*
Y-234972D01*
G01Y-232348D02*
X170359Y-233806D01*
X169048Y-234680D01*
X167520Y-234972D01*
X165774Y-234389D01*
X164464Y-232931D01*
X163590Y-231181D01*
X163372Y-229139D01*
X163590Y-227097D01*
X164464Y-225347D01*
X165774Y-223889D01*
X167520Y-223306D01*
X169048Y-223597D01*
X170140Y-224181D01*
X171232Y-225347D01*
G01X178252Y-240805D02*
X191352D01*
G01X197717Y-232639D02*
X199464Y-234097D01*
X201429Y-234972D01*
X203175D01*
X204922Y-234097D01*
X206232Y-232639D01*
X206887Y-230597D01*
X206450Y-228556D01*
X205359Y-226805D01*
X203394Y-225639D01*
X200774Y-225055D01*
X199245Y-223889D01*
X198590Y-221847D01*
X199027Y-219805D01*
X200119Y-218347D01*
X201647Y-217472D01*
X203175D01*
X204704Y-218055D01*
X206014Y-219514D01*
G01X215217Y-232639D02*
X216964Y-234097D01*
X218929Y-234972D01*
X220675D01*
X222422Y-234097D01*
X223732Y-232639D01*
X224387Y-230597D01*
X223950Y-228556D01*
X222859Y-226805D01*
X220894Y-225639D01*
X218274Y-225055D01*
X216745Y-223889D01*
X216090Y-221847D01*
X216527Y-219805D01*
X217619Y-218347D01*
X219147Y-217472D01*
X220675D01*
X222204Y-218055D01*
X223514Y-219514D01*
G01X250654Y-220389D02*
X251964Y-218639D01*
X253492Y-217764D01*
X255239Y-217472D01*
X257422Y-218055D01*
X258950Y-219514D01*
X259387Y-221263D01*
X259169Y-223014D01*
X258295Y-224472D01*
X253929Y-227389D01*
X251964Y-229430D01*
X250654Y-232348D01*
X250217Y-234972D01*
X259387D01*
G01X286527Y-232931D02*
X287619Y-234097D01*
X289147Y-234972D01*
X290457D01*
X291767Y-234389D01*
X292640Y-233514D01*
X293077Y-232348D01*
X292859Y-230597D01*
X291985Y-229722D01*
X288055Y-227972D01*
X287182Y-225930D01*
X287619Y-224472D01*
X288492Y-223597D01*
X289802Y-223306D01*
X291112Y-223597D01*
X292422Y-224472D01*
G01X307302Y-234972D02*
Y-217472D01*
G01X324802Y-234972D02*
X323492Y-234680D01*
X322182Y-233514D01*
X321308Y-231472D01*
X320872Y-229139D01*
X321308Y-226805D01*
X322182Y-224764D01*
X323492Y-223597D01*
X324802Y-223306D01*
X326112Y-223597D01*
X327422Y-224764D01*
X328295Y-226805D01*
X328514Y-229139D01*
X328295Y-231472D01*
X327422Y-233514D01*
X326112Y-234680D01*
X324802Y-234972D01*
G01X342302Y-217472D02*
Y-234972D01*
G01X339245Y-223306D02*
X345359D01*
G01X356527Y-232931D02*
X357619Y-234097D01*
X359147Y-234972D01*
X360457D01*
X361767Y-234389D01*
X362640Y-233514D01*
X363077Y-232348D01*
X362859Y-230597D01*
X361985Y-229722D01*
X358055Y-227972D01*
X357182Y-225930D01*
X357619Y-224472D01*
X358492Y-223597D01*
X359802Y-223306D01*
X361112Y-223597D01*
X362422Y-224472D01*
G01X109125Y-189972D02*
Y-172472D01*
X114802Y-187055D01*
X120479Y-172472D01*
Y-189972D01*
G01X132302D02*
X130992Y-189680D01*
X129682Y-188514D01*
X128808Y-186472D01*
X128372Y-184139D01*
X128808Y-181805D01*
X129682Y-179764D01*
X130992Y-178597D01*
X132302Y-178306D01*
X133612Y-178597D01*
X134922Y-179764D01*
X135795Y-181805D01*
X136014Y-184139D01*
X135795Y-186472D01*
X134922Y-188514D01*
X133612Y-189680D01*
X132302Y-189972D01*
G01X153732Y-172472D02*
Y-189972D01*
G01Y-187348D02*
X152859Y-188806D01*
X151548Y-189680D01*
X150020Y-189972D01*
X148274Y-189389D01*
X146964Y-187931D01*
X146090Y-186181D01*
X145872Y-184139D01*
X146090Y-182097D01*
X146964Y-180347D01*
X148274Y-178889D01*
X150020Y-178306D01*
X151548Y-178597D01*
X152640Y-179181D01*
X153732Y-180347D01*
G01X164027Y-182097D02*
X171014D01*
X170359Y-180055D01*
X169267Y-178889D01*
X167739Y-178306D01*
X166210Y-178597D01*
X164900Y-179472D01*
X164027Y-181514D01*
X163590Y-183264D01*
Y-185014D01*
X164027Y-186764D01*
X165119Y-188514D01*
X166429Y-189680D01*
X167957Y-189972D01*
X169485Y-189389D01*
X171014Y-187639D01*
G01X184802Y-189972D02*
Y-172472D01*
G01X418602Y-234972D02*
Y-217472D01*
X415982Y-220972D01*
G01Y-234972D02*
X421222D01*
G01X431299Y-232348D02*
X432608Y-233806D01*
X434137Y-234680D01*
X436102Y-234972D01*
X438067Y-234389D01*
X439595Y-233222D01*
X440687Y-231181D01*
X440905Y-228847D01*
X440469Y-226514D01*
X439377Y-225055D01*
X437848Y-223889D01*
X436320Y-223597D01*
X434792Y-223889D01*
X432827Y-225055D01*
X433482Y-217472D01*
X439377D01*
G01X449890Y-232931D02*
X451419Y-234389D01*
X453165Y-234972D01*
X454912Y-234389D01*
X456440Y-232639D01*
X457532Y-230014D01*
X457969Y-227389D01*
Y-224181D01*
X457532Y-221556D01*
X456440Y-219222D01*
X455130Y-218055D01*
X453602Y-217472D01*
X451855Y-218055D01*
X450545Y-219222D01*
X449672Y-220972D01*
X449235Y-223306D01*
X449672Y-225347D01*
X450764Y-227389D01*
X452074Y-228556D01*
X453602Y-228847D01*
X455348Y-228264D01*
X456659Y-226805D01*
X457969Y-224181D01*
G01X466954Y-227681D02*
X468482Y-225639D01*
X469792Y-224472D01*
X471539Y-223889D01*
X473067Y-224472D01*
X474159Y-225639D01*
X475032Y-227389D01*
X475250Y-229430D01*
X475032Y-231181D01*
X474159Y-232931D01*
X472848Y-234389D01*
X471320Y-234972D01*
X469574Y-234389D01*
X468045Y-232639D01*
X467172Y-230014D01*
X466954Y-227097D01*
X467390Y-223306D01*
X468045Y-221263D01*
X469137Y-219222D01*
X470665Y-217764D01*
X472194Y-217472D01*
X473722Y-218055D01*
X474814Y-219514D01*
G01X488602Y-234972D02*
X490130Y-234680D01*
X491877Y-233806D01*
X492969Y-232348D01*
X493405Y-230305D01*
X492969Y-228264D01*
X491659Y-226514D01*
X489694Y-225639D01*
X487510D01*
X486200Y-225055D01*
X485108Y-223597D01*
X484672Y-221556D01*
X485327Y-219514D01*
X486855Y-218055D01*
X488602Y-217472D01*
X490348Y-218055D01*
X491877Y-219514D01*
X492532Y-221556D01*
X492095Y-223597D01*
X491004Y-225055D01*
X489694Y-225639D01*
X487510D01*
X485545Y-226514D01*
X484235Y-228264D01*
X483799Y-230305D01*
X484235Y-232348D01*
X485327Y-233806D01*
X487074Y-234680D01*
X488602Y-234972D01*
G01X405485Y-189972D02*
Y-172472D01*
X410725D01*
X412472Y-173347D01*
X413782Y-175389D01*
X414219Y-177722D01*
X413782Y-180055D01*
X412690Y-181805D01*
X410725Y-182681D01*
X405485D01*
G01X432155Y-173931D02*
X430845Y-173055D01*
X429317Y-172472D01*
X427570D01*
X425605Y-173347D01*
X424077Y-174805D01*
X422985Y-176556D01*
X422112Y-179472D01*
X421893Y-182097D01*
X422330Y-184722D01*
X422985Y-186472D01*
X424295Y-188222D01*
X425824Y-189389D01*
X427352Y-189972D01*
X428880D01*
X430409Y-189389D01*
X431719Y-188514D01*
X432811Y-187348D01*
G01X446598Y-180639D02*
X447472Y-179764D01*
X448127Y-178306D01*
X448564Y-176263D01*
X448127Y-174514D01*
X447254Y-173347D01*
X445725Y-172472D01*
X439830D01*
Y-189972D01*
X447035D01*
X448564Y-188806D01*
X449437Y-187055D01*
X449874Y-185014D01*
X449437Y-182972D01*
X448127Y-181222D01*
X446598Y-180639D01*
X439830D01*
G01X455802Y-195805D02*
X468902D01*
G01X474830Y-189972D02*
Y-172472D01*
X484874Y-189972D01*
Y-172472D01*
G01X497352Y-189972D02*
X495605Y-189680D01*
X494077Y-188514D01*
X492767Y-186764D01*
X491893Y-184722D01*
X491457Y-182389D01*
Y-180055D01*
X491893Y-177722D01*
X492767Y-175680D01*
X494077Y-173931D01*
X495605Y-172764D01*
X497352Y-172472D01*
X499098Y-172764D01*
X500627Y-173931D01*
X501937Y-175680D01*
X502811Y-177722D01*
X503247Y-180055D01*
Y-182389D01*
X502811Y-184722D01*
X501937Y-186764D01*
X500627Y-188514D01*
X499098Y-189680D01*
X497352Y-189972D01*
G01X571152Y-234972D02*
Y-217472D01*
X568532Y-220972D01*
G01Y-234972D02*
X573772D01*
G01X583193D02*
X588652Y-217472D01*
X594111Y-234972D01*
G01X592145Y-228847D02*
X585158D01*
G01X548193Y-172472D02*
X553652Y-189972D01*
X559111Y-172472D01*
G01X575519Y-189972D02*
X566785D01*
Y-172472D01*
X575519D01*
G01X572025Y-180930D02*
X566785D01*
G01X584285Y-189972D02*
Y-172472D01*
X589744D01*
X591490Y-173347D01*
X592582Y-174514D01*
X593019Y-176847D01*
X592582Y-179181D01*
X591272Y-180639D01*
X589744Y-181514D01*
X584285D01*
G01X589744D02*
X593019Y-189972D01*
G01X606152Y-190555D02*
X605715Y-190264D01*
Y-189680D01*
X606152Y-189389D01*
X606589Y-189680D01*
Y-190264D01*
X606152Y-190555D01*
G01X745606Y-225639D02*
X744732Y-224764D01*
X744077Y-223306D01*
X743640Y-221263D01*
X744077Y-219514D01*
X744950Y-218347D01*
X746479Y-217472D01*
X752374D01*
Y-234972D01*
X745169D01*
X743640Y-233806D01*
X742767Y-232055D01*
X742330Y-230014D01*
X742767Y-227972D01*
X744077Y-226222D01*
X745606Y-225639D01*
X752374D01*
G01X734437Y-232639D02*
X732690Y-234097D01*
X730725Y-234972D01*
X728979D01*
X727232Y-234097D01*
X725922Y-232639D01*
X725267Y-230597D01*
X725704Y-228556D01*
X726795Y-226805D01*
X728760Y-225639D01*
X731380Y-225055D01*
X732909Y-223889D01*
X733564Y-221847D01*
X733127Y-219805D01*
X732035Y-218347D01*
X730507Y-217472D01*
X728979D01*
X727450Y-218055D01*
X726140Y-219514D01*
G01X718029Y-234972D02*
Y-217472D01*
X712352Y-232055D01*
X706675Y-217472D01*
Y-234972D01*
G01X699655D02*
Y-217472D01*
X695289D01*
X693542Y-218347D01*
X692232Y-219514D01*
X691140Y-221263D01*
X690267Y-223306D01*
X690049Y-226222D01*
X690267Y-229139D01*
X691140Y-231181D01*
X692232Y-232931D01*
X693542Y-234097D01*
X695289Y-234972D01*
X699655D01*
G01X681735Y-172472D02*
Y-189972D01*
X690469D01*
G01X707532D02*
Y-178306D01*
G01Y-180347D02*
X706659Y-179181D01*
X705348Y-178597D01*
X703820Y-178306D01*
X702292Y-178889D01*
X700982Y-180055D01*
X700108Y-181805D01*
X699672Y-184139D01*
X700108Y-186472D01*
X700982Y-188222D01*
X702292Y-189389D01*
X703820Y-189972D01*
X705348Y-189680D01*
X706659Y-188806D01*
X707532Y-187639D01*
G01X716517Y-195222D02*
X717827Y-195805D01*
X719574Y-195222D01*
X720665Y-194056D01*
X721539Y-192597D01*
X722848Y-187931D01*
X725687Y-178306D01*
G01X718700D02*
X722848Y-187931D01*
G01X735327Y-182097D02*
X742314D01*
X741659Y-180055D01*
X740567Y-178889D01*
X739039Y-178306D01*
X737510Y-178597D01*
X736200Y-179472D01*
X735327Y-181514D01*
X734890Y-183264D01*
Y-185014D01*
X735327Y-186764D01*
X736419Y-188514D01*
X737729Y-189680D01*
X739257Y-189972D01*
X740785Y-189389D01*
X742314Y-187639D01*
G01X753045Y-189972D02*
Y-178306D01*
G01Y-180639D02*
X754137Y-179472D01*
X755229Y-178597D01*
X756757Y-178306D01*
X757848Y-178597D01*
X759159Y-179472D01*
G01X824705Y-218931D02*
X823395Y-218055D01*
X821867Y-217472D01*
X820120D01*
X818155Y-218347D01*
X816627Y-219805D01*
X815535Y-221556D01*
X814662Y-224472D01*
X814443Y-227097D01*
X814880Y-229722D01*
X815535Y-231472D01*
X816845Y-233222D01*
X818374Y-234389D01*
X819902Y-234972D01*
X821430D01*
X822959Y-234389D01*
X824269Y-233514D01*
X825361Y-232348D01*
G01X837402Y-234972D02*
X835655Y-234680D01*
X834127Y-233514D01*
X832817Y-231764D01*
X831943Y-229722D01*
X831507Y-227389D01*
Y-225055D01*
X831943Y-222722D01*
X832817Y-220680D01*
X834127Y-218931D01*
X835655Y-217764D01*
X837402Y-217472D01*
X839148Y-217764D01*
X840677Y-218931D01*
X841987Y-220680D01*
X842861Y-222722D01*
X843297Y-225055D01*
Y-227389D01*
X842861Y-229722D01*
X841987Y-231764D01*
X840677Y-233514D01*
X839148Y-234680D01*
X837402Y-234972D01*
G01X849880D02*
Y-217472D01*
X859924Y-234972D01*
Y-217472D01*
G01X867380Y-234972D02*
Y-217472D01*
X877424Y-234972D01*
Y-217472D01*
G01X887282D02*
X892522D01*
G01X889902D02*
Y-234972D01*
G01X887282D02*
X892522D01*
G01X911769D02*
X903035D01*
Y-217472D01*
X911769D01*
G01X908275Y-225930D02*
X903035D01*
G01X937817Y-234972D02*
X946987Y-217472D01*
G01X937817D02*
X946987Y-234972D01*
G01X955317D02*
Y-217472D01*
G01X964487D02*
Y-234972D01*
G01Y-226222D02*
X955317D01*
G01X823849Y-189972D02*
Y-172472D01*
X828215D01*
X829962Y-173347D01*
X831272Y-174514D01*
X832364Y-176263D01*
X833237Y-178306D01*
X833455Y-181222D01*
X833237Y-184139D01*
X832364Y-186181D01*
X831272Y-187931D01*
X829962Y-189097D01*
X828215Y-189972D01*
X823849D01*
G01X842877Y-182097D02*
X849864D01*
X849209Y-180055D01*
X848117Y-178889D01*
X846589Y-178306D01*
X845060Y-178597D01*
X843750Y-179472D01*
X842877Y-181514D01*
X842440Y-183264D01*
Y-185014D01*
X842877Y-186764D01*
X843969Y-188514D01*
X845279Y-189680D01*
X846807Y-189972D01*
X848335Y-189389D01*
X849864Y-187639D01*
G01X860377Y-187931D02*
X861469Y-189097D01*
X862997Y-189972D01*
X864307D01*
X865617Y-189389D01*
X866490Y-188514D01*
X866927Y-187348D01*
X866709Y-185597D01*
X865835Y-184722D01*
X861905Y-182972D01*
X861032Y-180930D01*
X861469Y-179472D01*
X862342Y-178597D01*
X863652Y-178306D01*
X864962Y-178597D01*
X866272Y-179472D01*
G01X881152Y-178306D02*
Y-189972D01*
G01Y-173639D02*
X880715Y-173347D01*
Y-172764D01*
X881152Y-172472D01*
X881589Y-172764D01*
Y-173347D01*
X881152Y-173639D01*
G01X895595Y-194347D02*
X897124Y-195514D01*
X898870Y-195805D01*
X900398Y-195514D01*
X901709Y-194056D01*
X902582Y-192014D01*
Y-178306D01*
G01Y-180639D02*
X901709Y-179472D01*
X900398Y-178597D01*
X898870Y-178306D01*
X897124Y-178889D01*
X896032Y-180055D01*
X895158Y-182097D01*
X894722Y-184139D01*
X894940Y-185889D01*
X895814Y-187931D01*
X897124Y-189389D01*
X898870Y-189972D01*
X900180Y-189680D01*
X901709Y-188514D01*
X902582Y-187348D01*
G01X912440Y-189972D02*
Y-178306D01*
G01Y-181222D02*
X913314Y-179764D01*
X914624Y-178597D01*
X916370Y-178306D01*
X917898Y-178597D01*
X919209Y-179764D01*
X919864Y-181805D01*
Y-189972D01*
G01X930377Y-182097D02*
X937364D01*
X936709Y-180055D01*
X935617Y-178889D01*
X934089Y-178306D01*
X932560Y-178597D01*
X931250Y-179472D01*
X930377Y-181514D01*
X929940Y-183264D01*
Y-185014D01*
X930377Y-186764D01*
X931469Y-188514D01*
X932779Y-189680D01*
X934307Y-189972D01*
X935835Y-189389D01*
X937364Y-187639D01*
G01X948095Y-189972D02*
Y-178306D01*
G01Y-180639D02*
X949187Y-179472D01*
X950279Y-178597D01*
X951807Y-178306D01*
X952898Y-178597D01*
X954209Y-179472D01*
G01X994852Y-217472D02*
X993105Y-218055D01*
X991795Y-219514D01*
X990922Y-221263D01*
X990267Y-223597D01*
X990049Y-226222D01*
X990267Y-228847D01*
X990922Y-231181D01*
X991795Y-232931D01*
X993105Y-234389D01*
X994852Y-234972D01*
X996598Y-234389D01*
X997909Y-232931D01*
X998782Y-231181D01*
X999437Y-228847D01*
X999655Y-226222D01*
X999437Y-223597D01*
X998782Y-221263D01*
X997909Y-219514D01*
X996598Y-218055D01*
X994852Y-217472D01*
G01X1012352Y-234972D02*
X1013880Y-234680D01*
X1015627Y-233806D01*
X1016719Y-232348D01*
X1017155Y-230305D01*
X1016719Y-228264D01*
X1015409Y-226514D01*
X1013444Y-225639D01*
X1011260D01*
X1009950Y-225055D01*
X1008858Y-223597D01*
X1008422Y-221556D01*
X1009077Y-219514D01*
X1010605Y-218055D01*
X1012352Y-217472D01*
X1014098Y-218055D01*
X1015627Y-219514D01*
X1016282Y-221556D01*
X1015845Y-223597D01*
X1014754Y-225055D01*
X1013444Y-225639D01*
X1011260D01*
X1009295Y-226514D01*
X1007985Y-228264D01*
X1007549Y-230305D01*
X1007985Y-232348D01*
X1009077Y-233806D01*
X1010824Y-234680D01*
X1012352Y-234972D01*
G01X1025922Y-235555D02*
X1033782Y-217472D01*
G01X1043204Y-220389D02*
X1044514Y-218639D01*
X1046042Y-217764D01*
X1047789Y-217472D01*
X1049972Y-218055D01*
X1051500Y-219514D01*
X1051937Y-221263D01*
X1051719Y-223014D01*
X1050845Y-224472D01*
X1046479Y-227389D01*
X1044514Y-229430D01*
X1043204Y-232348D01*
X1042767Y-234972D01*
X1051937D01*
G01X1060049Y-232348D02*
X1061358Y-233806D01*
X1062887Y-234680D01*
X1064852Y-234972D01*
X1066817Y-234389D01*
X1068345Y-233222D01*
X1069437Y-231181D01*
X1069655Y-228847D01*
X1069219Y-226514D01*
X1068127Y-225055D01*
X1066598Y-223889D01*
X1065070Y-223597D01*
X1063542Y-223889D01*
X1061577Y-225055D01*
X1062232Y-217472D01*
X1068127D01*
G01X1078422Y-235555D02*
X1086282Y-217472D01*
G01X1095704Y-220389D02*
X1097014Y-218639D01*
X1098542Y-217764D01*
X1100289Y-217472D01*
X1102472Y-218055D01*
X1104000Y-219514D01*
X1104437Y-221263D01*
X1104219Y-223014D01*
X1103345Y-224472D01*
X1098979Y-227389D01*
X1097014Y-229430D01*
X1095704Y-232348D01*
X1095267Y-234972D01*
X1104437D01*
G01X1117352Y-217472D02*
X1115605Y-218055D01*
X1114295Y-219514D01*
X1113422Y-221263D01*
X1112767Y-223597D01*
X1112549Y-226222D01*
X1112767Y-228847D01*
X1113422Y-231181D01*
X1114295Y-232931D01*
X1115605Y-234389D01*
X1117352Y-234972D01*
X1119098Y-234389D01*
X1120409Y-232931D01*
X1121282Y-231181D01*
X1121937Y-228847D01*
X1122155Y-226222D01*
X1121937Y-223597D01*
X1121282Y-221263D01*
X1120409Y-219514D01*
X1119098Y-218055D01*
X1117352Y-217472D01*
G01X1134852Y-234972D02*
Y-217472D01*
X1132232Y-220972D01*
G01Y-234972D02*
X1137472D01*
G01X1148204Y-227681D02*
X1149732Y-225639D01*
X1151042Y-224472D01*
X1152789Y-223889D01*
X1154317Y-224472D01*
X1155409Y-225639D01*
X1156282Y-227389D01*
X1156500Y-229430D01*
X1156282Y-231181D01*
X1155409Y-232931D01*
X1154098Y-234389D01*
X1152570Y-234972D01*
X1150824Y-234389D01*
X1149295Y-232639D01*
X1148422Y-230014D01*
X1148204Y-227097D01*
X1148640Y-223306D01*
X1149295Y-221263D01*
X1150387Y-219222D01*
X1151915Y-217764D01*
X1153444Y-217472D01*
X1154972Y-218055D01*
X1156064Y-219514D01*
G01X1042549Y-189972D02*
Y-172472D01*
X1046915D01*
X1048662Y-173347D01*
X1049972Y-174514D01*
X1051064Y-176263D01*
X1051937Y-178306D01*
X1052155Y-181222D01*
X1051937Y-184139D01*
X1051064Y-186181D01*
X1049972Y-187931D01*
X1048662Y-189097D01*
X1046915Y-189972D01*
X1042549D01*
G01X1068782D02*
Y-178306D01*
G01Y-180347D02*
X1067909Y-179181D01*
X1066598Y-178597D01*
X1065070Y-178306D01*
X1063542Y-178889D01*
X1062232Y-180055D01*
X1061358Y-181805D01*
X1060922Y-184139D01*
X1061358Y-186472D01*
X1062232Y-188222D01*
X1063542Y-189389D01*
X1065070Y-189972D01*
X1066598Y-189680D01*
X1067909Y-188806D01*
X1068782Y-187639D01*
G01X1082352Y-172472D02*
Y-189972D01*
G01X1079295Y-178306D02*
X1085409D01*
G01X1096577Y-182097D02*
X1103564D01*
X1102909Y-180055D01*
X1101817Y-178889D01*
X1100289Y-178306D01*
X1098760Y-178597D01*
X1097450Y-179472D01*
X1096577Y-181514D01*
X1096140Y-183264D01*
Y-185014D01*
X1096577Y-186764D01*
X1097669Y-188514D01*
X1098979Y-189680D01*
X1100507Y-189972D01*
X1102035Y-189389D01*
X1103564Y-187639D01*
G54D34*
X51663Y63107D03*
G54D16*
X40900Y55100D03*
G54D25*
X34600Y79000D03*
X78700Y60000D03*
X36100Y67300D03*
G54D26*
X36800Y59800D03*
X44500Y70800D03*
X42100Y91000D03*
G54D17*
X62700Y85600D03*
X70300D03*
G54D35*
X51563Y76493D03*
X62437Y63107D03*
G54D18*
X32300Y74900D03*
G54D36*
X51563Y74524D03*
Y72950D03*
Y71375D03*
Y69800D03*
Y68225D03*
Y66650D03*
Y65076D03*
G54D27*
X36800Y63200D03*
X44500Y74200D03*
X42100Y94400D03*
G54D28*
X43000Y80700D03*
G54D19*
X32300Y71300D03*
G54D37*
X30900Y62650D03*
G54D29*
X39600Y80700D03*
G54D38*
X30900Y59950D03*
G54D39*
X85100Y30700D03*
Y23100D03*
Y41900D03*
Y49500D03*
X77400Y41900D03*
Y49500D03*
Y30700D03*
Y23100D03*
M02*
